(kicad_pcb
	(version 20260206)
	(generator "pcbnew")
	(generator_version "10.0")
	(general
		(thickness 1.6)
		(legacy_teardrops no)
	)
	(paper "A4")
	(title_block
		(title "Wiwynn_Tioga_Pass_MB.brd")
		(comment 1 "Tioga Pass / footprint 4543 of 4770 (J9U2), pads 1-123 of 291")
	)
	(layers
		(0 "F.Cu" signal "TOP")
		(4 "In1.Cu" signal "L2GND")
		(6 "In2.Cu" signal "L3")
		(8 "In3.Cu" signal "L4GND")
		(10 "In4.Cu" signal "L5")
		(12 "In5.Cu" signal "L6GND")
		(14 "In6.Cu" signal "L7VCC")
		(16 "In7.Cu" signal "L8VCC")
		(18 "In8.Cu" signal "L9GND")
		(20 "In9.Cu" signal "L10")
		(22 "In10.Cu" signal "L11GND")
		(24 "In11.Cu" signal "L12")
		(26 "In12.Cu" signal "L13GND")
		(2 "B.Cu" signal "BOTTOM")
		(9 "F.Adhes" user "F.Adhesive")
		(11 "B.Adhes" user "B.Adhesive")
		(13 "F.Paste" user "Package Geometry/Pastemask Top")
		(15 "B.Paste" user "Package Geometry/Pastemask Bottom")
		(5 "F.SilkS" user "Ref Des/Silkscreen Top")
		(7 "B.SilkS" user "Ref Des/Silkscreen Bottom")
		(1 "F.Mask" user "Board Geometry/Soldermask Top")
		(3 "B.Mask" user "Board Geometry/Soldermask Bottom")
		(17 "Dwgs.User" user "User.Drawings")
		(19 "Cmts.User" user "User.Comments")
		(21 "Eco1.User" user "User.Eco1")
		(23 "Eco2.User" user "User.Eco2")
		(25 "Edge.Cuts" user "Board Geometry/Outline")
		(27 "Margin" user)
		(31 "F.CrtYd" user "Package Geometry/Place Bound Top")
		(29 "B.CrtYd" user "Package Geometry/Place Bound Bottom")
		(35 "F.Fab" user "Ref Des/Assembly Top")
		(33 "B.Fab" user "Ref Des/Assembly Bottom")
	)
	(footprint ""
		(layer "B.Cu")
		(at 29.699458 -5.621782 90)
		(property "Reference" "J9U2"
			(at 2.098548 38.118542 0)
			(unlocked yes)
			(layer "B.SilkS")
			(effects
				(font
					(size 0.7874 0.5842)
					(thickness 0.1524)
				)
				(justify left mirror)
			)
		)
		(property "Value" ""
			(at 0 0 90)
			(layer "B.Fab")
			(effects
				(font
					(size 1.27 1.27)
				)
				(justify mirror)
			)
		)
		(duplicate_pad_numbers_are_jumpers no)
		(pad "" thru_hole circle
			(at -2.29997 -5.649976 270)
			(size 2.8194 2.8194)
			(drill 2.4384)
			(layers "*.Cu" "*.Mask")
			(remove_unused_layers no)
			(clearance 0.127)
			(thermal_gap 0.127)
		)
		(pad "" thru_hole oval
			(at -2.29997 68.90004 270)
			(size 2.8194 1.5748)
			(drill oval 2.4384 1.1938)
			(layers "*.Cu" "*.Mask")
			(remove_unused_layers no)
			(clearance 0.127)
			(thermal_gap 0.127)
		)
		(pad "" thru_hole circle
			(at -2.29997 132.299964 270)
			(size 2.8194 2.8194)
			(drill 2.4384)
			(layers "*.Cu" "*.Mask")
			(remove_unused_layers no)
			(clearance 0.127)
			(thermal_gap 0.127)
		)
		(pad "1" smd rect
			(at 0 0 270)
			(size 1.8034 0.508)
			(layers "B.Cu" "B.Mask" "B.Paste")
			(net "P12V_NVDIMM_GHJ")
		)
		(pad "2" smd rect
			(at 0 0.849884 270)
			(size 1.8034 0.508)
			(layers "B.Cu" "B.Mask" "B.Paste")
			(net "GND")
		)
		(pad "3" smd rect
			(at 0 1.700022 270)
			(size 1.8034 0.508)
			(layers "B.Cu" "B.Mask" "B.Paste")
			(net "M_J_DQ<4>")
		)
		(pad "4" smd rect
			(at 0 2.549906 270)
			(size 1.8034 0.508)
			(layers "B.Cu" "B.Mask" "B.Paste")
			(net "GND")
		)
		(pad "5" smd rect
			(at 0 3.400044 270)
			(size 1.8034 0.508)
			(layers "B.Cu" "B.Mask" "B.Paste")
			(net "M_J_DQ<0>")
		)
		(pad "6" smd rect
			(at 0 4.249928 270)
			(size 1.8034 0.508)
			(layers "B.Cu" "B.Mask" "B.Paste")
			(net "GND")
		)
		(pad "7" smd rect
			(at 0 5.100066 270)
			(size 1.8034 0.508)
			(layers "B.Cu" "B.Mask" "B.Paste")
			(net "M_J_DQS_DP<9>")
		)
		(pad "8" smd rect
			(at 0 5.94995 270)
			(size 1.8034 0.508)
			(layers "B.Cu" "B.Mask" "B.Paste")
			(net "M_J_DQS_DN<9>")
		)
		(pad "9" smd rect
			(at 0 6.800088 270)
			(size 1.8034 0.508)
			(layers "B.Cu" "B.Mask" "B.Paste")
			(net "GND")
		)
		(pad "10" smd rect
			(at 0 7.649972 270)
			(size 1.8034 0.508)
			(layers "B.Cu" "B.Mask" "B.Paste")
			(net "M_J_DQ<6>")
		)
		(pad "11" smd rect
			(at 0 8.50011 270)
			(size 1.8034 0.508)
			(layers "B.Cu" "B.Mask" "B.Paste")
			(net "GND")
		)
		(pad "12" smd rect
			(at 0 9.349994 270)
			(size 1.8034 0.508)
			(layers "B.Cu" "B.Mask" "B.Paste")
			(net "M_J_DQ<2>")
		)
		(pad "13" smd rect
			(at 0 10.199878 270)
			(size 1.8034 0.508)
			(layers "B.Cu" "B.Mask" "B.Paste")
			(net "GND")
		)
		(pad "14" smd rect
			(at 0 11.050016 270)
			(size 1.8034 0.508)
			(layers "B.Cu" "B.Mask" "B.Paste")
			(net "M_J_DQ<12>")
		)
		(pad "15" smd rect
			(at 0 11.8999 270)
			(size 1.8034 0.508)
			(layers "B.Cu" "B.Mask" "B.Paste")
			(net "GND")
		)
		(pad "16" smd rect
			(at 0 12.750038 270)
			(size 1.8034 0.508)
			(layers "B.Cu" "B.Mask" "B.Paste")
			(net "M_J_DQ<8>")
		)
		(pad "17" smd rect
			(at 0 13.599922 270)
			(size 1.8034 0.508)
			(layers "B.Cu" "B.Mask" "B.Paste")
			(net "GND")
		)
		(pad "18" smd rect
			(at 0 14.45006 270)
			(size 1.8034 0.508)
			(layers "B.Cu" "B.Mask" "B.Paste")
			(net "M_J_DQS_DP<10>")
		)
		(pad "19" smd rect
			(at 0 15.299944 270)
			(size 1.8034 0.508)
			(layers "B.Cu" "B.Mask" "B.Paste")
			(net "M_J_DQS_DN<10>")
		)
		(pad "20" smd rect
			(at 0 16.150082 270)
			(size 1.8034 0.508)
			(layers "B.Cu" "B.Mask" "B.Paste")
			(net "GND")
		)
		(pad "21" smd rect
			(at 0 16.999966 270)
			(size 1.8034 0.508)
			(layers "B.Cu" "B.Mask" "B.Paste")
			(net "M_J_DQ<14>")
		)
		(pad "22" smd rect
			(at 0 17.850104 270)
			(size 1.8034 0.508)
			(layers "B.Cu" "B.Mask" "B.Paste")
			(net "GND")
		)
		(pad "23" smd rect
			(at 0 18.699988 270)
			(size 1.8034 0.508)
			(layers "B.Cu" "B.Mask" "B.Paste")
			(net "M_J_DQ<10>")
		)
		(pad "24" smd rect
			(at 0 19.550126 270)
			(size 1.8034 0.508)
			(layers "B.Cu" "B.Mask" "B.Paste")
			(net "GND")
		)
		(pad "25" smd rect
			(at 0 20.40001 270)
			(size 1.8034 0.508)
			(layers "B.Cu" "B.Mask" "B.Paste")
			(net "M_J_DQ<20>")
		)
		(pad "26" smd rect
			(at 0 21.249894 270)
			(size 1.8034 0.508)
			(layers "B.Cu" "B.Mask" "B.Paste")
			(net "GND")
		)
		(pad "27" smd rect
			(at 0 22.100032 270)
			(size 1.8034 0.508)
			(layers "B.Cu" "B.Mask" "B.Paste")
			(net "M_J_DQ<16>")
		)
		(pad "28" smd rect
			(at 0 22.949916 270)
			(size 1.8034 0.508)
			(layers "B.Cu" "B.Mask" "B.Paste")
			(net "GND")
		)
		(pad "29" smd rect
			(at 0 23.800054 270)
			(size 1.8034 0.508)
			(layers "B.Cu" "B.Mask" "B.Paste")
			(net "M_J_DQS_DP<11>")
		)
		(pad "30" smd rect
			(at 0 24.649938 270)
			(size 1.8034 0.508)
			(layers "B.Cu" "B.Mask" "B.Paste")
			(net "M_J_DQS_DN<11>")
		)
		(pad "31" smd rect
			(at 0 25.500076 270)
			(size 1.8034 0.508)
			(layers "B.Cu" "B.Mask" "B.Paste")
			(net "GND")
		)
		(pad "32" smd rect
			(at 0 26.34996 270)
			(size 1.8034 0.508)
			(layers "B.Cu" "B.Mask" "B.Paste")
			(net "M_J_DQ<22>")
		)
		(pad "33" smd rect
			(at 0 27.200098 270)
			(size 1.8034 0.508)
			(layers "B.Cu" "B.Mask" "B.Paste")
			(net "GND")
		)
		(pad "34" smd rect
			(at 0 28.049982 270)
			(size 1.8034 0.508)
			(layers "B.Cu" "B.Mask" "B.Paste")
			(net "M_J_DQ<18>")
		)
		(pad "35" smd rect
			(at 0 28.90012 270)
			(size 1.8034 0.508)
			(layers "B.Cu" "B.Mask" "B.Paste")
			(net "GND")
		)
		(pad "36" smd rect
			(at 0 29.750004 270)
			(size 1.8034 0.508)
			(layers "B.Cu" "B.Mask" "B.Paste")
			(net "M_J_DQ<28>")
		)
		(pad "37" smd rect
			(at 0 30.599888 270)
			(size 1.8034 0.508)
			(layers "B.Cu" "B.Mask" "B.Paste")
			(net "GND")
		)
		(pad "38" smd rect
			(at 0 31.450026 270)
			(size 1.8034 0.508)
			(layers "B.Cu" "B.Mask" "B.Paste")
			(net "M_J_DQ<24>")
		)
		(pad "39" smd rect
			(at 0 32.29991 270)
			(size 1.8034 0.508)
			(layers "B.Cu" "B.Mask" "B.Paste")
			(net "GND")
		)
		(pad "40" smd rect
			(at 0 33.150048 270)
			(size 1.8034 0.508)
			(layers "B.Cu" "B.Mask" "B.Paste")
			(net "M_J_DQS_DP<12>")
		)
		(pad "41" smd rect
			(at 0 33.999932 270)
			(size 1.8034 0.508)
			(layers "B.Cu" "B.Mask" "B.Paste")
			(net "M_J_DQS_DN<12>")
		)
		(pad "42" smd rect
			(at 0 34.85007 270)
			(size 1.8034 0.508)
			(layers "B.Cu" "B.Mask" "B.Paste")
			(net "GND")
		)
		(pad "43" smd rect
			(at 0 35.699954 270)
			(size 1.8034 0.508)
			(layers "B.Cu" "B.Mask" "B.Paste")
			(net "M_J_DQ<30>")
		)
		(pad "44" smd rect
			(at 0 36.550092 270)
			(size 1.8034 0.508)
			(layers "B.Cu" "B.Mask" "B.Paste")
			(net "GND")
		)
		(pad "45" smd rect
			(at 0 37.399976 270)
			(size 1.8034 0.508)
			(layers "B.Cu" "B.Mask" "B.Paste")
			(net "M_J_DQ<26>")
		)
		(pad "46" smd rect
			(at 0 38.250114 270)
			(size 1.8034 0.508)
			(layers "B.Cu" "B.Mask" "B.Paste")
			(net "GND")
		)
		(pad "47" smd rect
			(at 0 39.099998 270)
			(size 1.8034 0.508)
			(layers "B.Cu" "B.Mask" "B.Paste")
			(net "M_J_ECC<4>")
		)
		(pad "48" smd rect
			(at 0 39.949882 270)
			(size 1.8034 0.508)
			(layers "B.Cu" "B.Mask" "B.Paste")
			(net "GND")
		)
		(pad "49" smd rect
			(at 0 40.80002 270)
			(size 1.8034 0.508)
			(layers "B.Cu" "B.Mask" "B.Paste")
			(net "M_J_ECC<0>")
		)
		(pad "50" smd rect
			(at 0 41.649904 270)
			(size 1.8034 0.508)
			(layers "B.Cu" "B.Mask" "B.Paste")
			(net "GND")
		)
		(pad "51" smd rect
			(at 0 42.500042 270)
			(size 1.8034 0.508)
			(layers "B.Cu" "B.Mask" "B.Paste")
			(net "M_J_DQS_DP<17>")
		)
		(pad "52" smd rect
			(at 0 43.349926 270)
			(size 1.8034 0.508)
			(layers "B.Cu" "B.Mask" "B.Paste")
			(net "M_J_DQS_DN<17>")
		)
		(pad "53" smd rect
			(at 0 44.200064 270)
			(size 1.8034 0.508)
			(layers "B.Cu" "B.Mask" "B.Paste")
			(net "GND")
		)
		(pad "54" smd rect
			(at 0 45.049948 270)
			(size 1.8034 0.508)
			(layers "B.Cu" "B.Mask" "B.Paste")
			(net "M_J_ECC<6>")
		)
		(pad "55" smd rect
			(at 0 45.900086 270)
			(size 1.8034 0.508)
			(layers "B.Cu" "B.Mask" "B.Paste")
			(net "GND")
		)
		(pad "56" smd rect
			(at 0 46.74997 270)
			(size 1.8034 0.508)
			(layers "B.Cu" "B.Mask" "B.Paste")
			(net "M_J_ECC<2>")
		)
		(pad "57" smd rect
			(at 0 47.600108 270)
			(size 1.8034 0.508)
			(layers "B.Cu" "B.Mask" "B.Paste")
			(net "GND")
		)
		(pad "58" smd rect
			(at 0 48.449992 270)
			(size 1.8034 0.508)
			(layers "B.Cu" "B.Mask" "B.Paste")
			(net "M_GHJ_RST_N")
		)
		(pad "59" smd rect
			(at 0 49.299876 270)
			(size 1.8034 0.508)
			(layers "B.Cu" "B.Mask" "B.Paste")
			(net "PVDDQ_GHJ")
		)
		(pad "60" smd rect
			(at 0 50.150014 270)
			(size 1.8034 0.508)
			(layers "B.Cu" "B.Mask" "B.Paste")
			(net "M_J_CKE<2>")
		)
		(pad "61" smd rect
			(at 0 50.999898 270)
			(size 1.8034 0.508)
			(layers "B.Cu" "B.Mask" "B.Paste")
			(net "PVDDQ_GHJ")
		)
		(pad "62" smd rect
			(at 0 51.850036 270)
			(size 1.8034 0.508)
			(layers "B.Cu" "B.Mask" "B.Paste")
			(net "M_J_ACT_N")
		)
		(pad "63" smd rect
			(at 0 52.69992 270)
			(size 1.8034 0.508)
			(layers "B.Cu" "B.Mask" "B.Paste")
			(net "M_J_BG<0>")
		)
		(pad "64" smd rect
			(at 0 53.550058 270)
			(size 1.8034 0.508)
			(layers "B.Cu" "B.Mask" "B.Paste")
			(net "PVDDQ_GHJ")
		)
		(pad "65" smd rect
			(at 0 54.399942 270)
			(size 1.8034 0.508)
			(layers "B.Cu" "B.Mask" "B.Paste")
			(net "M_J_MA<12>")
		)
		(pad "66" smd rect
			(at 0 55.25008 270)
			(size 1.8034 0.508)
			(layers "B.Cu" "B.Mask" "B.Paste")
			(net "M_J_MA<9>")
		)
		(pad "67" smd rect
			(at 0 56.099964 270)
			(size 1.8034 0.508)
			(layers "B.Cu" "B.Mask" "B.Paste")
			(net "PVDDQ_GHJ")
		)
		(pad "68" smd rect
			(at 0 56.950102 270)
			(size 1.8034 0.508)
			(layers "B.Cu" "B.Mask" "B.Paste")
			(net "M_J_MA<8>")
		)
		(pad "69" smd rect
			(at 0 57.799986 270)
			(size 1.8034 0.508)
			(layers "B.Cu" "B.Mask" "B.Paste")
			(net "M_J_MA<6>")
		)
		(pad "70" smd rect
			(at 0 58.650124 270)
			(size 1.8034 0.508)
			(layers "B.Cu" "B.Mask" "B.Paste")
			(net "PVDDQ_GHJ")
		)
		(pad "71" smd rect
			(at 0 59.500008 270)
			(size 1.8034 0.508)
			(layers "B.Cu" "B.Mask" "B.Paste")
			(net "M_J_MA<3>")
		)
		(pad "72" smd rect
			(at 0 60.349892 270)
			(size 1.8034 0.508)
			(layers "B.Cu" "B.Mask" "B.Paste")
			(net "M_J_MA<1>")
		)
		(pad "73" smd rect
			(at 0 61.20003 270)
			(size 1.8034 0.508)
			(layers "B.Cu" "B.Mask" "B.Paste")
			(net "PVDDQ_GHJ")
		)
		(pad "74" smd rect
			(at 0 62.049914 270)
			(size 1.8034 0.508)
			(layers "B.Cu" "B.Mask" "B.Paste")
			(net "M_J_CLK_DP<2>")
		)
		(pad "75" smd rect
			(at 0 62.900052 270)
			(size 1.8034 0.508)
			(layers "B.Cu" "B.Mask" "B.Paste")
			(net "M_J_CLK_DN<2>")
		)
		(pad "76" smd rect
			(at 0 63.749936 270)
			(size 1.8034 0.508)
			(layers "B.Cu" "B.Mask" "B.Paste")
			(net "PVDDQ_GHJ")
		)
		(pad "77" smd rect
			(at 0 64.600074 270)
			(size 1.8034 0.508)
			(layers "B.Cu" "B.Mask" "B.Paste")
			(net "PVTT_GHJ")
		)
		(pad "78" smd rect
			(at 0 70.550024 270)
			(size 1.8034 0.508)
			(layers "B.Cu" "B.Mask" "B.Paste")
			(net "FM_DIMM_EVENT_COD_N")
		)
		(pad "79" smd rect
			(at 0 71.399908 270)
			(size 1.8034 0.508)
			(layers "B.Cu" "B.Mask" "B.Paste")
			(net "M_J_MA<0>")
		)
		(pad "80" smd rect
			(at 0 72.250046 270)
			(size 1.8034 0.508)
			(layers "B.Cu" "B.Mask" "B.Paste")
			(net "PVDDQ_GHJ")
		)
		(pad "81" smd rect
			(at 0 73.09993 270)
			(size 1.8034 0.508)
			(layers "B.Cu" "B.Mask" "B.Paste")
			(net "M_J_BA<0>")
		)
		(pad "82" smd rect
			(at 0 73.950068 270)
			(size 1.8034 0.508)
			(layers "B.Cu" "B.Mask" "B.Paste")
			(net "M_J_MA<16>")
		)
		(pad "83" smd rect
			(at 0 74.799952 270)
			(size 1.8034 0.508)
			(layers "B.Cu" "B.Mask" "B.Paste")
			(net "PVDDQ_GHJ")
		)
		(pad "84" smd rect
			(at 0 75.65009 270)
			(size 1.8034 0.508)
			(layers "B.Cu" "B.Mask" "B.Paste")
			(net "M_J_CS_N<4>")
		)
		(pad "85" smd rect
			(at 0 76.499974 270)
			(size 1.8034 0.508)
			(layers "B.Cu" "B.Mask" "B.Paste")
			(net "PVDDQ_GHJ")
		)
		(pad "86" smd rect
			(at 0 77.350112 270)
			(size 1.8034 0.508)
			(layers "B.Cu" "B.Mask" "B.Paste")
			(net "M_J_MA<15>")
		)
		(pad "87" smd rect
			(at 0 78.199996 270)
			(size 1.8034 0.508)
			(layers "B.Cu" "B.Mask" "B.Paste")
			(net "M_J_ODT<2>")
		)
		(pad "88" smd rect
			(at 0 79.04988 270)
			(size 1.8034 0.508)
			(layers "B.Cu" "B.Mask" "B.Paste")
			(net "PVDDQ_GHJ")
		)
		(pad "89" smd rect
			(at 0 79.900018 270)
			(size 1.8034 0.508)
			(layers "B.Cu" "B.Mask" "B.Paste")
			(net "M_J_CS_N<5>")
		)
		(pad "90" smd rect
			(at 0 80.749902 270)
			(size 1.8034 0.508)
			(layers "B.Cu" "B.Mask" "B.Paste")
			(net "PVDDQ_GHJ")
		)
		(pad "91" smd rect
			(at 0 81.60004 270)
			(size 1.8034 0.508)
			(layers "B.Cu" "B.Mask" "B.Paste")
			(net "M_J_ODT<3>")
		)
		(pad "92" smd rect
			(at 0 82.449924 270)
			(size 1.8034 0.508)
			(layers "B.Cu" "B.Mask" "B.Paste")
			(net "PVDDQ_GHJ")
		)
		(pad "93" smd rect
			(at 0 83.300062 270)
			(size 1.8034 0.508)
			(layers "B.Cu" "B.Mask" "B.Paste")
			(net "M_J_CS_N<6>")
		)
		(pad "94" smd rect
			(at 0 84.149946 270)
			(size 1.8034 0.508)
			(layers "B.Cu" "B.Mask" "B.Paste")
			(net "GND")
		)
		(pad "95" smd rect
			(at 0 85.000084 270)
			(size 1.8034 0.508)
			(layers "B.Cu" "B.Mask" "B.Paste")
			(net "M_J_DQ<36>")
		)
		(pad "96" smd rect
			(at 0 85.849968 270)
			(size 1.8034 0.508)
			(layers "B.Cu" "B.Mask" "B.Paste")
			(net "GND")
		)
		(pad "97" smd rect
			(at 0 86.700106 270)
			(size 1.8034 0.508)
			(layers "B.Cu" "B.Mask" "B.Paste")
			(net "M_J_DQ<32>")
		)
		(pad "98" smd rect
			(at 0 87.54999 270)
			(size 1.8034 0.508)
			(layers "B.Cu" "B.Mask" "B.Paste")
			(net "GND")
		)
		(pad "99" smd rect
			(at 0 88.399874 270)
			(size 1.8034 0.508)
			(layers "B.Cu" "B.Mask" "B.Paste")
			(net "M_J_DQS_DP<13>")
		)
		(pad "100" smd rect
			(at 0 89.250012 270)
			(size 1.8034 0.508)
			(layers "B.Cu" "B.Mask" "B.Paste")
			(net "M_J_DQS_DN<13>")
		)
		(pad "101" smd rect
			(at 0 90.099896 270)
			(size 1.8034 0.508)
			(layers "B.Cu" "B.Mask" "B.Paste")
			(net "GND")
		)
		(pad "102" smd rect
			(at 0 90.950034 270)
			(size 1.8034 0.508)
			(layers "B.Cu" "B.Mask" "B.Paste")
			(net "M_J_DQ<38>")
		)
		(pad "103" smd rect
			(at 0 91.799918 270)
			(size 1.8034 0.508)
			(layers "B.Cu" "B.Mask" "B.Paste")
			(net "GND")
		)
		(pad "104" smd rect
			(at 0 92.650056 270)
			(size 1.8034 0.508)
			(layers "B.Cu" "B.Mask" "B.Paste")
			(net "M_J_DQ<34>")
		)
		(pad "105" smd rect
			(at 0 93.49994 270)
			(size 1.8034 0.508)
			(layers "B.Cu" "B.Mask" "B.Paste")
			(net "GND")
		)
		(pad "106" smd rect
			(at 0 94.350078 270)
			(size 1.8034 0.508)
			(layers "B.Cu" "B.Mask" "B.Paste")
			(net "M_J_DQ<44>")
		)
		(pad "107" smd rect
			(at 0 95.199962 270)
			(size 1.8034 0.508)
			(layers "B.Cu" "B.Mask" "B.Paste")
			(net "GND")
		)
		(pad "108" smd rect
			(at 0 96.0501 270)
			(size 1.8034 0.508)
			(layers "B.Cu" "B.Mask" "B.Paste")
			(net "M_J_DQ<40>")
		)
		(pad "109" smd rect
			(at 0 96.899984 270)
			(size 1.8034 0.508)
			(layers "B.Cu" "B.Mask" "B.Paste")
			(net "GND")
		)
		(pad "110" smd rect
			(at 0 97.750122 270)
			(size 1.8034 0.508)
			(layers "B.Cu" "B.Mask" "B.Paste")
			(net "M_J_DQS_DP<14>")
		)
		(pad "111" smd rect
			(at 0 98.600006 270)
			(size 1.8034 0.508)
			(layers "B.Cu" "B.Mask" "B.Paste")
			(net "M_J_DQS_DN<14>")
		)
		(pad "112" smd rect
			(at 0 99.44989 270)
			(size 1.8034 0.508)
			(layers "B.Cu" "B.Mask" "B.Paste")
			(net "GND")
		)
		(pad "113" smd rect
			(at 0 100.300028 270)
			(size 1.8034 0.508)
			(layers "B.Cu" "B.Mask" "B.Paste")
			(net "M_J_DQ<46>")
		)
		(pad "114" smd rect
			(at 0 101.149912 270)
			(size 1.8034 0.508)
			(layers "B.Cu" "B.Mask" "B.Paste")
			(net "GND")
		)
		(pad "115" smd rect
			(at 0 102.00005 270)
			(size 1.8034 0.508)
			(layers "B.Cu" "B.Mask" "B.Paste")
			(net "M_J_DQ<42>")
		)
		(pad "116" smd rect
			(at 0 102.849934 270)
			(size 1.8034 0.508)
			(layers "B.Cu" "B.Mask" "B.Paste")
			(net "GND")
		)
		(pad "117" smd rect
			(at 0 103.700072 270)
			(size 1.8034 0.508)
			(layers "B.Cu" "B.Mask" "B.Paste")
			(net "M_J_DQ<52>")
		)
		(pad "118" smd rect
			(at 0 104.549956 270)
			(size 1.8034 0.508)
			(layers "B.Cu" "B.Mask" "B.Paste")
			(net "GND")
		)
		(pad "119" smd rect
			(at 0 105.400094 270)
			(size 1.8034 0.508)
			(layers "B.Cu" "B.Mask" "B.Paste")
			(net "M_J_DQ<48>")
		)
		(pad "120" smd rect
			(at 0 106.249978 270)
			(size 1.8034 0.508)
			(layers "B.Cu" "B.Mask" "B.Paste")
			(net "GND")
		)
	)
)
